FILE_TYPE = CONNECTIVITY;
{Allegro Design Entry HDL 16.6-p007 (v16-6-112F) 10/10/2012}
"PAGE_NUMBER" = 32;
0"NC";
1"P3E_CPU0_PE3_OCP_TXN<15:0>";
2"P3E_CPU0_PE3_OCP_TXP<15:0>";
3"P3E_CPU0_PE3_OCP_RXN<15:0>";
4"P3E_CPU0_PE3_OCP_RXP<15:0>";
5"P3E_CPU0_PE3_OCP_RXP<15>";
6"P3E_CPU0_PE3_OCP_RXP<9>";
7"P3E_CPU0_PE3_OCP_RXP<11>";
8"P3E_CPU0_PE3_OCP_RXN<15>";
9"P3E_CPU0_PE3_OCP_RXP<4>";
10"P3E_CPU0_PE3_OCP_RXP<5>";
11"P3E_CPU0_PE3_OCP_RXP<7>";
12"P3E_CPU0_PE3_OCP_TXN<14>";
13"P3E_CPU0_PE3_OCP_TXN<15>";
14"P3E_CPU0_PE3_OCP_TXN<11>";
15"P3E_CPU0_PE3_OCP_RXN<14>";
16"P3E_CPU0_PE3_OCP_RXN<11>";
17"P3E_CPU0_PE3_OCP_RXN<10>";
18"P3E_CPU0_PE3_OCP_RXN<9>";
19"P3E_CPU0_PE3_OCP_RXN<8>";
20"P3E_CPU0_PE3_OCP_RXP<6>";
21"P3E_CPU0_PE3_OCP_TXN<8>";
22"P3E_CPU0_PE3_OCP_TXN<9>";
23"P3E_CPU0_PE3_OCP_RXN<12>";
24"P3E_CPU0_PE3_OCP_RXP<12>";
25"P3E_CPU0_PE3_OCP_RXP<10>";
26"P3E_CPU0_PE3_OCP_RXN<0>";
27"P3E_CPU0_PE3_OCP_RXN<3>";
28"P3E_CPU0_PE3_OCP_RXP<0>";
29"P3E_CPU0_PE3_OCP_RXP<1>";
30"P3E_CPU0_PE3_OCP_RXP<2>";
31"P3E_CPU0_PE3_OCP_RXP<3>";
32"P3E_CPU0_PE3_OCP_RXN<1>";
33"P3E_CPU0_PE3_OCP_RXN<2>";
34"P3E_CPU0_PE3_OCP_RXP<8>";
35"P3E_CPU0_PE3_OCP_RXP<13>";
36"P3E_CPU0_PE3_OCP_RXP<14>";
37"P3E_CPU0_PE3_OCP_RXN<4>";
38"P3E_CPU0_PE3_OCP_RXN<5>";
39"P3E_CPU0_PE3_OCP_RXN<6>";
40"P3E_CPU0_PE3_OCP_RXN<7>";
41"P3E_CPU0_PE3_OCP_RXN<13>";
42"P3E_CPU0_PE3_OCP_TXP<0>";
43"P3E_CPU0_PE3_OCP_TXP<1>";
44"P3E_CPU0_PE3_OCP_TXP<2>";
45"P3E_CPU0_PE3_OCP_TXP<3>";
46"P3E_CPU0_PE3_OCP_TXN<0>";
47"P3E_CPU0_PE3_OCP_TXN<1>";
48"P3E_CPU0_PE3_OCP_TXN<2>";
49"P3E_CPU0_PE3_OCP_TXN<3>";
50"P3E_CPU0_PE3_OCP_TXP<4>";
51"P3E_CPU0_PE3_OCP_TXP<5>";
52"P3E_CPU0_PE3_OCP_TXP<6>";
53"P3E_CPU0_PE3_OCP_TXP<7>";
54"P3E_CPU0_PE3_OCP_TXP<8>";
55"P3E_CPU0_PE3_OCP_TXP<9>";
56"P3E_CPU0_PE3_OCP_TXP<10>";
57"P3E_CPU0_PE3_OCP_TXP<11>";
58"P3E_CPU0_PE3_OCP_TXP<12>";
59"P3E_CPU0_PE3_OCP_TXP<13>";
60"P3E_CPU0_PE3_OCP_TXP<14>";
61"P3E_CPU0_PE3_OCP_TXP<15>";
62"P3E_CPU0_PE3_OCP_TXN<4>";
63"P3E_CPU0_PE3_OCP_TXN<5>";
64"P3E_CPU0_PE3_OCP_TXN<6>";
65"P3E_CPU0_PE3_OCP_TXN<7>";
66"P3E_CPU0_PE3_OCP_TXN<10>";
67"P3E_CPU0_PE3_OCP_TXN<12>";
68"P3E_CPU0_PE3_OCP_TXN<13>";
%"TAP"
"1","(-5875,2025)","2","mstr_standard","I15";
;
CDS_LIB"mstr_standard"
BODY_TYPE"PLUMBING"
HDL_TAP"TRUE";
"B \NAC \NWC"4;
"S \NAC"
BN"3"31;
%"TAP"
"1","(-6025,2625)","2","mstr_standard","I20";
;
CDS_LIB"mstr_standard"
BODY_TYPE"PLUMBING"
HDL_TAP"TRUE";
"B \NAC \NWC"3;
"S \NAC"
BN"8"19;
%"TAP"
"1","(-6025,2675)","2","mstr_standard","I21";
;
CDS_LIB"mstr_standard"
BODY_TYPE"PLUMBING"
HDL_TAP"TRUE";
"B \NAC \NWC"3;
"S \NAC"
BN"9"18;
%"TAP"
"1","(-6025,2725)","2","mstr_standard","I22";
;
CDS_LIB"mstr_standard"
BODY_TYPE"PLUMBING"
HDL_TAP"TRUE";
"B \NAC \NWC"3;
"S \NAC"
BN"10"17;
%"TAP"
"1","(-6025,2775)","2","mstr_standard","I23";
;
CDS_LIB"mstr_standard"
BODY_TYPE"PLUMBING"
HDL_TAP"TRUE";
"B \NAC \NWC"3;
"S \NAC"
BN"11"16;
%"TAP"
"1","(-5875,2875)","2","mstr_standard","I24";
;
CDS_LIB"mstr_standard"
BODY_TYPE"PLUMBING"
HDL_TAP"TRUE";
"B \NAC \NWC"4;
"S \NAC"
BN"8"34;
%"TAP"
"1","(-5875,2975)","2","mstr_standard","I25";
;
CDS_LIB"mstr_standard"
BODY_TYPE"PLUMBING"
HDL_TAP"TRUE";
"B \NAC \NWC"4;
"S \NAC"
BN"10"25;
%"TAP"
"1","(-5875,2925)","2","mstr_standard","I26";
;
CDS_LIB"mstr_standard"
BODY_TYPE"PLUMBING"
HDL_TAP"TRUE";
"B \NAC \NWC"4;
"S \NAC"
BN"9"6;
%"TAP"
"1","(-5875,3025)","2","mstr_standard","I27";
;
CDS_LIB"mstr_standard"
BODY_TYPE"PLUMBING"
HDL_TAP"TRUE";
"B \NAC \NWC"4;
"S \NAC"
BN"11"7;
%"TAP"
"1","(-6025,3125)","2","mstr_standard","I28";
;
CDS_LIB"mstr_standard"
BODY_TYPE"PLUMBING"
HDL_TAP"TRUE";
"B \NAC \NWC"3;
"S \NAC"
BN"12"23;
%"TAP"
"1","(-6025,3175)","2","mstr_standard","I29";
;
CDS_LIB"mstr_standard"
BODY_TYPE"PLUMBING"
HDL_TAP"TRUE";
"B \NAC \NWC"3;
"S \NAC"
BN"13"41;
%"TAP"
"1","(-6025,1625)","2","mstr_standard","I3";
;
CDS_LIB"mstr_standard"
BODY_TYPE"PLUMBING"
HDL_TAP"TRUE";
"B \NAC \NWC"3;
"S \NAC"
BN"0"26;
%"TAP"
"1","(-6025,3275)","2","mstr_standard","I30";
;
CDS_LIB"mstr_standard"
BODY_TYPE"PLUMBING"
HDL_TAP"TRUE";
"B \NAC \NWC"3;
"S \NAC"
BN"15"8;
%"TAP"
"1","(-6025,3225)","2","mstr_standard","I31";
;
CDS_LIB"mstr_standard"
BODY_TYPE"PLUMBING"
HDL_TAP"TRUE";
"B \NAC \NWC"3;
"S \NAC"
BN"14"15;
%"TAP"
"1","(-5875,3375)","2","mstr_standard","I32";
;
CDS_LIB"mstr_standard"
BODY_TYPE"PLUMBING"
HDL_TAP"TRUE";
"B \NAC \NWC"4;
"S \NAC"
BN"12"24;
%"TAP"
"1","(-5875,3425)","2","mstr_standard","I33";
;
CDS_LIB"mstr_standard"
BODY_TYPE"PLUMBING"
HDL_TAP"TRUE";
"B \NAC \NWC"4;
"S \NAC"
BN"13"35;
%"TAP"
"1","(-5875,3475)","2","mstr_standard","I34";
;
CDS_LIB"mstr_standard"
BODY_TYPE"PLUMBING"
HDL_TAP"TRUE";
"B \NAC \NWC"4;
"S \NAC"
BN"14"36;
%"TAP"
"1","(-5875,3525)","2","mstr_standard","I35";
;
CDS_LIB"mstr_standard"
BODY_TYPE"PLUMBING"
HDL_TAP"TRUE";
"B \NAC \NWC"4;
"S \NAC"
BN"15"5;
%"TAP"
"1","(-3000,1875)","0","mstr_standard","I36";
;
CDS_LIB"mstr_standard"
BODY_TYPE"PLUMBING"
HDL_TAP"TRUE";
"B \NAC \NWC"2;
"S \NAC"
BN"0"42;
%"TAP"
"1","(-3000,1975)","0","mstr_standard","I37";
;
CDS_LIB"mstr_standard"
BODY_TYPE"PLUMBING"
HDL_TAP"TRUE";
"B \NAC \NWC"2;
"S \NAC"
BN"2"44;
%"TAP"
"1","(-3000,1925)","0","mstr_standard","I38";
;
CDS_LIB"mstr_standard"
BODY_TYPE"PLUMBING"
HDL_TAP"TRUE";
"B \NAC \NWC"2;
"S \NAC"
BN"1"43;
%"TAP"
"1","(-2850,1625)","0","mstr_standard","I39";
;
CDS_LIB"mstr_standard"
BODY_TYPE"PLUMBING"
HDL_TAP"TRUE";
"B \NAC \NWC"1;
"S \NAC"
BN"0"46;
%"TAP"
"1","(-6025,1675)","2","mstr_standard","I4";
;
CDS_LIB"mstr_standard"
BODY_TYPE"PLUMBING"
HDL_TAP"TRUE";
"B \NAC \NWC"3;
"S \NAC"
BN"1"32;
%"TAP"
"1","(-2850,1675)","0","mstr_standard","I40";
;
CDS_LIB"mstr_standard"
BODY_TYPE"PLUMBING"
HDL_TAP"TRUE";
"B \NAC \NWC"1;
"S \NAC"
BN"1"47;
%"TAP"
"1","(-2850,1725)","0","mstr_standard","I41";
;
CDS_LIB"mstr_standard"
BODY_TYPE"PLUMBING"
HDL_TAP"TRUE";
"B \NAC \NWC"1;
"S \NAC"
BN"2"48;
%"TAP"
"1","(-2850,1775)","0","mstr_standard","I42";
;
CDS_LIB"mstr_standard"
BODY_TYPE"PLUMBING"
HDL_TAP"TRUE";
"B \NAC \NWC"1;
"S \NAC"
BN"3"49;
%"TAP"
"1","(-3000,2475)","0","mstr_standard","I43";
;
CDS_LIB"mstr_standard"
BODY_TYPE"PLUMBING"
HDL_TAP"TRUE";
"B \NAC \NWC"2;
"S \NAC"
BN"6"52;
%"TAP"
"1","(-3000,2525)","0","mstr_standard","I44";
;
CDS_LIB"mstr_standard"
BODY_TYPE"PLUMBING"
HDL_TAP"TRUE";
"B \NAC \NWC"2;
"S \NAC"
BN"7"53;
%"TAP"
"1","(-3000,2425)","0","mstr_standard","I45";
;
CDS_LIB"mstr_standard"
BODY_TYPE"PLUMBING"
HDL_TAP"TRUE";
"B \NAC \NWC"2;
"S \NAC"
BN"5"51;
%"TAP"
"1","(-3000,2375)","0","mstr_standard","I46";
;
CDS_LIB"mstr_standard"
BODY_TYPE"PLUMBING"
HDL_TAP"TRUE";
"B \NAC \NWC"2;
"S \NAC"
BN"4"50;
%"TAP"
"1","(-3000,2025)","0","mstr_standard","I47";
;
CDS_LIB"mstr_standard"
BODY_TYPE"PLUMBING"
HDL_TAP"TRUE";
"B \NAC \NWC"2;
"S \NAC"
BN"3"45;
%"TAP"
"1","(-2850,2125)","0","mstr_standard","I48";
;
CDS_LIB"mstr_standard"
BODY_TYPE"PLUMBING"
HDL_TAP"TRUE";
"B \NAC \NWC"1;
"S \NAC"
BN"4"62;
%"TAP"
"1","(-2850,2175)","0","mstr_standard","I49";
;
CDS_LIB"mstr_standard"
BODY_TYPE"PLUMBING"
HDL_TAP"TRUE";
"B \NAC \NWC"1;
"S \NAC"
BN"5"63;
%"TAP"
"1","(-6025,1725)","2","mstr_standard","I5";
;
CDS_LIB"mstr_standard"
BODY_TYPE"PLUMBING"
HDL_TAP"TRUE";
"B \NAC \NWC"3;
"S \NAC"
BN"2"33;
%"TAP"
"1","(-2850,2225)","0","mstr_standard","I50";
;
CDS_LIB"mstr_standard"
BODY_TYPE"PLUMBING"
HDL_TAP"TRUE";
"B \NAC \NWC"1;
"S \NAC"
BN"6"64;
%"TAP"
"1","(-2850,2275)","0","mstr_standard","I51";
;
CDS_LIB"mstr_standard"
BODY_TYPE"PLUMBING"
HDL_TAP"TRUE";
"B \NAC \NWC"1;
"S \NAC"
BN"7"65;
%"TAP"
"1","(-3000,2975)","0","mstr_standard","I52";
;
CDS_LIB"mstr_standard"
BODY_TYPE"PLUMBING"
HDL_TAP"TRUE";
"B \NAC \NWC"2;
"S \NAC"
BN"10"56;
%"TAP"
"1","(-3000,3025)","0","mstr_standard","I53";
;
CDS_LIB"mstr_standard"
BODY_TYPE"PLUMBING"
HDL_TAP"TRUE";
"B \NAC \NWC"2;
"S \NAC"
BN"11"57;
%"TAP"
"1","(-3000,2925)","0","mstr_standard","I54";
;
CDS_LIB"mstr_standard"
BODY_TYPE"PLUMBING"
HDL_TAP"TRUE";
"B \NAC \NWC"2;
"S \NAC"
BN"9"55;
%"TAP"
"1","(-3000,2875)","0","mstr_standard","I55";
;
CDS_LIB"mstr_standard"
BODY_TYPE"PLUMBING"
HDL_TAP"TRUE";
"B \NAC \NWC"2;
"S \NAC"
BN"8"54;
%"TAP"
"1","(-2850,2625)","0","mstr_standard","I56";
;
CDS_LIB"mstr_standard"
BODY_TYPE"PLUMBING"
HDL_TAP"TRUE";
"B \NAC \NWC"1;
"S \NAC"
BN"8"21;
%"TAP"
"1","(-2850,2725)","0","mstr_standard","I57";
;
CDS_LIB"mstr_standard"
BODY_TYPE"PLUMBING"
HDL_TAP"TRUE";
"B \NAC \NWC"1;
"S \NAC"
BN"10"66;
%"TAP"
"1","(-2850,2675)","0","mstr_standard","I58";
;
CDS_LIB"mstr_standard"
BODY_TYPE"PLUMBING"
HDL_TAP"TRUE";
"B \NAC \NWC"1;
"S \NAC"
BN"9"22;
%"TAP"
"1","(-2850,2775)","0","mstr_standard","I59";
;
CDS_LIB"mstr_standard"
BODY_TYPE"PLUMBING"
HDL_TAP"TRUE";
"B \NAC \NWC"1;
"S \NAC"
BN"11"14;
%"TAP"
"1","(-6025,1775)","2","mstr_standard","I6";
;
CDS_LIB"mstr_standard"
BODY_TYPE"PLUMBING"
HDL_TAP"TRUE";
"B \NAC \NWC"3;
"S \NAC"
BN"3"27;
%"TAP"
"1","(-3000,3425)","0","mstr_standard","I60";
;
CDS_LIB"mstr_standard"
BODY_TYPE"PLUMBING"
HDL_TAP"TRUE";
"B \NAC \NWC"2;
"S \NAC"
BN"13"59;
%"TAP"
"1","(-3000,3525)","0","mstr_standard","I61";
;
CDS_LIB"mstr_standard"
BODY_TYPE"PLUMBING"
HDL_TAP"TRUE";
"B \NAC \NWC"2;
"S \NAC"
BN"15"61;
%"TAP"
"1","(-3000,3375)","0","mstr_standard","I62";
;
CDS_LIB"mstr_standard"
BODY_TYPE"PLUMBING"
HDL_TAP"TRUE";
"B \NAC \NWC"2;
"S \NAC"
BN"12"58;
%"TAP"
"1","(-3000,3475)","0","mstr_standard","I63";
;
CDS_LIB"mstr_standard"
BODY_TYPE"PLUMBING"
HDL_TAP"TRUE";
"B \NAC \NWC"2;
"S \NAC"
BN"14"60;
%"TAP"
"1","(-2850,3125)","0","mstr_standard","I64";
;
CDS_LIB"mstr_standard"
BODY_TYPE"PLUMBING"
HDL_TAP"TRUE";
"B \NAC \NWC"1;
"S \NAC"
BN"12"67;
%"TAP"
"1","(-2850,3175)","0","mstr_standard","I65";
;
CDS_LIB"mstr_standard"
BODY_TYPE"PLUMBING"
HDL_TAP"TRUE";
"B \NAC \NWC"1;
"S \NAC"
BN"13"68;
%"TAP"
"1","(-2850,3275)","0","mstr_standard","I66";
;
CDS_LIB"mstr_standard"
BODY_TYPE"PLUMBING"
HDL_TAP"TRUE";
"B \NAC \NWC"1;
"S \NAC"
BN"15"13;
%"TAP"
"1","(-2850,3225)","0","mstr_standard","I67";
;
CDS_LIB"mstr_standard"
BODY_TYPE"PLUMBING"
HDL_TAP"TRUE";
"B \NAC \NWC"1;
"S \NAC"
BN"14"12;
%"TAP"
"1","(-5875,1875)","2","mstr_standard","I7";
;
CDS_LIB"mstr_standard"
BODY_TYPE"PLUMBING"
HDL_TAP"TRUE";
"B \NAC \NWC"4;
"S \NAC"
BN"0"28;
%"TAP"
"1","(-5875,1925)","2","mstr_standard","I8";
;
CDS_LIB"mstr_standard"
BODY_TYPE"PLUMBING"
HDL_TAP"TRUE";
"B \NAC \NWC"4;
"S \NAC"
BN"1"29;
%"TAP"
"6","(-5875,2525)","0","mstr_standard","I81";
;
CDS_LIB"mstr_standard"
BODY_TYPE"PLUMBING"
HDL_TAP"TRUE";
"B \NAC \NWC"4;
"S \NAC"
BN"7"11;
%"TAP"
"6","(-5875,2475)","0","mstr_standard","I82";
;
CDS_LIB"mstr_standard"
BODY_TYPE"PLUMBING"
HDL_TAP"TRUE";
"B \NAC \NWC"4;
"S \NAC"
BN"6"20;
%"TAP"
"6","(-5875,2425)","0","mstr_standard","I83";
;
CDS_LIB"mstr_standard"
BODY_TYPE"PLUMBING"
HDL_TAP"TRUE";
"B \NAC \NWC"4;
"S \NAC"
BN"5"10;
%"TAP"
"6","(-5875,2375)","0","mstr_standard","I84";
;
CDS_LIB"mstr_standard"
BODY_TYPE"PLUMBING"
HDL_TAP"TRUE";
"B \NAC \NWC"4;
"S \NAC"
BN"4"9;
%"TAP"
"6","(-6025,2275)","0","mstr_standard","I85";
;
CDS_LIB"mstr_standard"
BODY_TYPE"PLUMBING"
HDL_TAP"TRUE";
"B \NAC \NWC"3;
"S \NAC"
BN"7"40;
%"TAP"
"6","(-6025,2225)","0","mstr_standard","I86";
;
CDS_LIB"mstr_standard"
BODY_TYPE"PLUMBING"
HDL_TAP"TRUE";
"B \NAC \NWC"3;
"S \NAC"
BN"6"39;
%"TAP"
"6","(-6025,2175)","0","mstr_standard","I87";
;
CDS_LIB"mstr_standard"
BODY_TYPE"PLUMBING"
HDL_TAP"TRUE";
"B \NAC \NWC"3;
"S \NAC"
BN"5"38;
%"TAP"
"6","(-6025,2125)","0","mstr_standard","I88";
;
CDS_LIB"mstr_standard"
BODY_TYPE"PLUMBING"
HDL_TAP"TRUE";
"B \NAC \NWC"3;
"S \NAC"
BN"4"37;
%"SKX_EXT_B"
"12","(-4200,2575)","0","chpset_lib","I89";
;
CDS_SEC"12"
LOCATION"U5D1"
PART_NUMBER"TBD"
MATERIAL"IC"
PACK_TYPE"BGA1"
CDS_LIB"chpset_lib"
SEC_TYPE"BGA1"
SEC"12"
CDS_LOCATION"U5D1";
"PE3_TX_DP<0>"
$PN"EC14"42;
"PE3_TX_DP<1>"
$PN"ED13"43;
"PE3_TX_DP<2>"
$PN"EB11"44;
"PE3_TX_DP<3>"
$PN"EA10"45;
"PE3_TX_DP<4>"
$PN"DY9"50;
"PE3_TX_DP<5>"
$PN"DV9"51;
"PE3_TX_DP<6>"
$PN"DT9"52;
"PE3_TX_DP<7>"
$PN"DP7"53;
"PE3_TX_DP<8>"
$PN"DN6"54;
"PE3_TX_DP<9>"
$PN"DM5"55;
"PE3_TX_DP<10>"
$PN"DK5"56;
"PE3_TX_DP<11>"
$PN"DH5"57;
"PE3_TX_DP<12>"
$PN"DG6"58;
"PE3_TX_DP<13>"
$PN"DC6"59;
"PE3_TX_DP<14>"
$PN"DA4"60;
"PE3_TX_DP<15>"
$PN"CV5"61;
"PE3_TX_DN<0>"
$PN"EE14"46;
"PE3_TX_DN<1>"
$PN"EE12"47;
"PE3_TX_DN<2>"
$PN"EC12"48;
"PE3_TX_DN<3>"
$PN"DY11"49;
"PE3_TX_DN<4>"
$PN"EB9"62;
"PE3_TX_DN<5>"
$PN"DW10"63;
"PE3_TX_DN<6>"
$PN"DU8"64;
"PE3_TX_DN<7>"
$PN"DR8"65;
"PE3_TX_DN<8>"
$PN"DM7"21;
"PE3_TX_DN<9>"
$PN"DP5"22;
"PE3_TX_DN<10>"
$PN"DL6"66;
"PE3_TX_DN<11>"
$PN"DJ4"14;
"PE3_TX_DN<12>"
$PN"DJ6"67;
"PE3_TX_DN<13>"
$PN"DD5"68;
"PE3_TX_DN<14>"
$PN"DB5"12;
"PE3_TX_DN<15>"
$PN"CY5"13;
"PE3_RX_DP<0>"
$PN"DY17"28;
"PE3_RX_DP<1>"
$PN"DU18"29;
"PE3_RX_DP<2>"
$PN"DV17"30;
"PE3_RX_DP<3>"
$PN"DR18"31;
"PE3_RX_DP<4>"
$PN"DN16"9;
"PE3_RX_DP<5>"
$PN"DP15"10;
"PE3_RX_DP<6>"
$PN"DM13"20;
"PE3_RX_DP<7>"
$PN"DJ14"11;
"PE3_RX_DP<8>"
$PN"DK13"34;
"PE3_RX_DP<9>"
$PN"DH11"6;
"PE3_RX_DP<10>"
$PN"DE12"25;
"PE3_RX_DP<11>"
$PN"DF11"7;
"PE3_RX_DP<12>"
$PN"DC12"24;
"PE3_RX_DP<13>"
$PN"DA12"35;
"PE3_RX_DP<14>"
$PN"CW10"36;
"PE3_RX_DP<15>"
$PN"CU10"5;
"PE3_RX_DN<0>"
$PN"EA18"26;
"PE3_RX_DN<1>"
$PN"DW18"32;
"PE3_RX_DN<2>"
$PN"DW16"33;
"PE3_RX_DN<3>"
$PN"DT19"27;
"PE3_RX_DN<4>"
$PN"DR16"37;
"PE3_RX_DN<5>"
$PN"DR14"38;
"PE3_RX_DN<6>"
$PN"DN14"39;
"PE3_RX_DN<7>"
$PN"DL14"40;
"PE3_RX_DN<8>"
$PN"DL12"19;
"PE3_RX_DN<9>"
$PN"DJ12"18;
"PE3_RX_DN<10>"
$PN"DG12"17;
"PE3_RX_DN<11>"
$PN"DG10"16;
"PE3_RX_DN<12>"
$PN"DD13"23;
"PE3_RX_DN<13>"
$PN"DB11"41;
"PE3_RX_DN<14>"
$PN"CY11"15;
"PE3_RX_DN<15>"
$PN"CV9"8;
%"TAP"
"1","(-5875,1975)","2","mstr_standard","I9";
;
CDS_LIB"mstr_standard"
BODY_TYPE"PLUMBING"
HDL_TAP"TRUE";
"B \NAC \NWC"4;
"S \NAC"
BN"2"30;
END.
